(kicad_pcb
	(version 20240108)
	(generator "pcbnew")
	(generator_version "8.0")
	(general
		(thickness 1.62)
		(legacy_teardrops no)
	)
	(paper "A4")
	(title_block
		(title "Jetson Orin Baseboard")
		(date "2025-03-12")
		(rev "1.3.4")
		(company "Antmicro Ltd")
		(comment 1 "www.antmicro.com")
		(comment 9 "footprints 595-599 of 677")
	)
	(layers
		(0 "F.Cu" signal)
		(1 "In1.Cu" signal)
		(2 "In2.Cu" signal)
		(3 "In3.Cu" signal)
		(4 "In4.Cu" jumper)
		(5 "In5.Cu" signal)
		(6 "In6.Cu" signal)
		(31 "B.Cu" signal)
		(32 "B.Adhes" user "B.Adhesive")
		(33 "F.Adhes" user "F.Adhesive")
		(34 "B.Paste" user)
		(35 "F.Paste" user)
		(36 "B.SilkS" user "B.Silkscreen")
		(37 "F.SilkS" user "F.Silkscreen")
		(38 "B.Mask" user)
		(39 "F.Mask" user)
		(40 "Dwgs.User" user "User.Drawings")
		(41 "Cmts.User" user "User.Comments")
		(42 "Eco1.User" user "User.Eco1")
		(43 "Eco2.User" user "User.Eco2")
		(44 "Edge.Cuts" user)
		(45 "Margin" user)
		(46 "B.CrtYd" user "B.Courtyard")
		(47 "F.CrtYd" user "F.Courtyard")
		(48 "B.Fab" user)
		(49 "F.Fab" user)
	)
	(footprint "antmicro-footprints:C_0402_1005Metric"
		(layer "B.Cu")
		(at 39.608 117.856 -90)
		(descr "Capacitor SMD 0402")
		(tags "capacitor SMD 0402")
		(property "Reference" "C78"
			(at -1.206 1.458 90)
			(layer "B.SilkS")
			(effects
				(font
					(size 0.7 0.7)
					(thickness 0.15)
				)
				(justify left bottom mirror)
			)
		)
		(property "Value" "C_100n_0402"
			(at 0 -1.4 90)
			(layer "B.Fab")
			(effects
				(font
					(size 0.7 0.7)
					(thickness 0.15)
				)
				(justify left bottom mirror)
			)
		)
		(property "Footprint" "antmicro-footprints:C_0402_1005Metric"
			(at 0 0 -90)
			(layer "F.Fab")
			(hide yes)
			(effects
				(font
					(size 1.27 1.27)
					(thickness 0.15)
				)
			)
		)
		(property "Datasheet" "https://www.murata.com/products/productdetail?partno=GRM155R61H104KE14%23"
			(at 0 0 -90)
			(layer "F.Fab")
			(hide yes)
			(effects
				(font
					(size 1.27 1.27)
					(thickness 0.15)
				)
			)
		)
		(property "Author" "Antmicro"
			(at -78.248 157.464 0)
			(layer "B.Fab")
			(hide yes)
			(effects
				(font
					(size 1 1)
					(thickness 0.15)
				)
				(justify mirror)
			)
		)
		(property "Dielectric" "X5R"
			(at -78.248 157.464 0)
			(layer "B.Fab")
			(hide yes)
			(effects
				(font
					(size 1 1)
					(thickness 0.15)
				)
				(justify mirror)
			)
		)
		(property "License" "Apache-2.0"
			(at -78.248 157.464 0)
			(layer "B.Fab")
			(hide yes)
			(effects
				(font
					(size 1 1)
					(thickness 0.15)
				)
				(justify mirror)
			)
		)
		(property "MPN" "GRM155R61H104KE14D"
			(at -78.248 157.464 0)
			(layer "B.Fab")
			(hide yes)
			(effects
				(font
					(size 1 1)
					(thickness 0.15)
				)
				(justify mirror)
			)
		)
		(property "Manufacturer" "Murata"
			(at -78.248 157.464 0)
			(layer "B.Fab")
			(hide yes)
			(effects
				(font
					(size 1 1)
					(thickness 0.15)
				)
				(justify mirror)
			)
		)
		(property "Val" "100n"
			(at -78.248 157.464 0)
			(layer "B.Fab")
			(hide yes)
			(effects
				(font
					(size 1 1)
					(thickness 0.15)
				)
				(justify mirror)
			)
		)
		(property "Voltage" "50V"
			(at -78.248 157.464 0)
			(layer "B.Fab")
			(hide yes)
			(effects
				(font
					(size 1 1)
					(thickness 0.15)
				)
				(justify mirror)
			)
		)
		(sheetname "Ethernet")
		(sheetfile "ethernet.kicad_sch")
		(attr smd)
		(fp_rect
			(start -0.925 0.47)
			(end 0.925 -0.47)
			(stroke
				(width 0.05)
				(type default)
			)
			(fill none)
			(layer "B.CrtYd")
		)
		(fp_line
			(start -0.494 0.25)
			(end -0.494 -0.248)
			(stroke
				(width 0.15)
				(type solid)
			)
			(layer "B.Fab")
		)
		(fp_line
			(start 0.504 0.25)
			(end -0.494 0.25)
			(stroke
				(width 0.15)
				(type solid)
			)
			(layer "B.Fab")
		)
		(fp_line
			(start -0.494 -0.248)
			(end 0.504 -0.248)
			(stroke
				(width 0.15)
				(type solid)
			)
			(layer "B.Fab")
		)
		(fp_line
			(start 0.504 -0.248)
			(end 0.504 0.25)
			(stroke
				(width 0.15)
				(type solid)
			)
			(layer "B.Fab")
		)
		(fp_text user "License: Apache-2.0"
			(at -0.932 -5.17 90)
			(layer "B.Fab")
			(hide yes)
			(effects
				(font
					(size 0.7 0.7)
					(thickness 0.15)
				)
				(justify left bottom mirror)
			)
		)
		(fp_text user "Author: Antmicro"
			(at -0.932 -4.17 90)
			(layer "B.Fab")
			(hide yes)
			(effects
				(font
					(size 0.7 0.7)
					(thickness 0.15)
				)
				(justify left bottom mirror)
			)
		)
		(fp_text user "${REFERENCE}"
			(at -0.932 -3.168 90)
			(layer "B.Fab")
			(hide yes)
			(effects
				(font
					(size 0.7 0.7)
					(thickness 0.15)
				)
				(justify left bottom mirror)
			)
		)
		(pad "1" smd roundrect
			(at -0.48 0 270)
			(size 0.59 0.64)
			(layers "B.Cu" "B.Paste" "B.Mask")
			(roundrect_rratio 0.25)
			(net 715 "Net-(C78-Pad1)")
			(pintype "passive")
		)
		(pad "2" smd roundrect
			(at 0.48 0 270)
			(size 0.59 0.64)
			(layers "B.Cu" "B.Paste" "B.Mask")
			(roundrect_rratio 0.25)
			(net 1 "GND")
			(pintype "passive")
		)
	)
	(footprint "antmicro-footprints:C_0402_1005Metric"
		(layer "B.Cu")
		(at 126.735 89.75)
		(descr "Capacitor SMD 0402")
		(tags "capacitor SMD 0402")
		(property "Reference" "C15"
			(at 2.965 0.45 180)
			(layer "B.SilkS")
			(effects
				(font
					(size 0.7 0.7)
					(thickness 0.15)
				)
				(justify left bottom mirror)
			)
		)
		(property "Value" "C_220n_0402"
			(at 0 -1.4 180)
			(layer "B.Fab")
			(effects
				(font
					(size 0.7 0.7)
					(thickness 0.15)
				)
				(justify left bottom mirror)
			)
		)
		(property "Footprint" "antmicro-footprints:C_0402_1005Metric"
			(at 0 0 0)
			(layer "F.Fab")
			(hide yes)
			(effects
				(font
					(size 1.27 1.27)
					(thickness 0.15)
				)
			)
		)
		(property "Datasheet" "https://www.yageo.com/en/Chart/Download/pdf/CC0402KRX5R6BB224"
			(at 0 0 0)
			(layer "F.Fab")
			(hide yes)
			(effects
				(font
					(size 1.27 1.27)
					(thickness 0.15)
				)
			)
		)
		(property "Author" "Antmicro"
			(at 0 0 0)
			(layer "B.Fab")
			(hide yes)
			(effects
				(font
					(size 1 1)
					(thickness 0.15)
				)
				(justify mirror)
			)
		)
		(property "Dielectric" ""
			(at 0 0 0)
			(layer "B.Fab")
			(hide yes)
			(effects
				(font
					(size 1 1)
					(thickness 0.15)
				)
				(justify mirror)
			)
		)
		(property "License" "Apache-2.0"
			(at 0 0 0)
			(layer "B.Fab")
			(hide yes)
			(effects
				(font
					(size 1 1)
					(thickness 0.15)
				)
				(justify mirror)
			)
		)
		(property "MPN" "CC0402KRX5R6BB224"
			(at 0 0 0)
			(layer "B.Fab")
			(hide yes)
			(effects
				(font
					(size 1 1)
					(thickness 0.15)
				)
				(justify mirror)
			)
		)
		(property "Manufacturer" "YAGEO"
			(at 0 0 0)
			(layer "B.Fab")
			(hide yes)
			(effects
				(font
					(size 1 1)
					(thickness 0.15)
				)
				(justify mirror)
			)
		)
		(property "Val" "220n"
			(at 0 0 0)
			(layer "B.Fab")
			(hide yes)
			(effects
				(font
					(size 1 1)
					(thickness 0.15)
				)
				(justify mirror)
			)
		)
		(property "Voltage" ""
			(at 0 0 0)
			(layer "B.Fab")
			(hide yes)
			(effects
				(font
					(size 1 1)
					(thickness 0.15)
				)
				(justify mirror)
			)
		)
		(sheetname "M.2")
		(sheetfile "m-2.kicad_sch")
		(attr smd)
		(fp_rect
			(start -0.925 0.47)
			(end 0.925 -0.47)
			(stroke
				(width 0.05)
				(type default)
			)
			(fill none)
			(layer "B.CrtYd")
		)
		(fp_line
			(start -0.494 -0.248)
			(end 0.504 -0.248)
			(stroke
				(width 0.15)
				(type solid)
			)
			(layer "B.Fab")
		)
		(fp_line
			(start -0.494 0.25)
			(end -0.494 -0.248)
			(stroke
				(width 0.15)
				(type solid)
			)
			(layer "B.Fab")
		)
		(fp_line
			(start 0.504 -0.248)
			(end 0.504 0.25)
			(stroke
				(width 0.15)
				(type solid)
			)
			(layer "B.Fab")
		)
		(fp_line
			(start 0.504 0.25)
			(end -0.494 0.25)
			(stroke
				(width 0.15)
				(type solid)
			)
			(layer "B.Fab")
		)
		(fp_text user "Author: Antmicro"
			(at -0.932 -4.17 180)
			(layer "B.Fab")
			(hide yes)
			(effects
				(font
					(size 0.7 0.7)
					(thickness 0.15)
				)
				(justify left bottom mirror)
			)
		)
		(fp_text user "${REFERENCE}"
			(at -0.932 -3.168 180)
			(layer "B.Fab")
			(hide yes)
			(effects
				(font
					(size 0.7 0.7)
					(thickness 0.15)
				)
				(justify left bottom mirror)
			)
		)
		(fp_text user "License: Apache-2.0"
			(at -0.932 -5.17 180)
			(layer "B.Fab")
			(hide yes)
			(effects
				(font
					(size 0.7 0.7)
					(thickness 0.15)
				)
				(justify left bottom mirror)
			)
		)
		(pad "1" smd roundrect
			(at -0.48 0)
			(size 0.59 0.64)
			(layers "B.Cu" "B.Paste" "B.Mask")
			(roundrect_rratio 0.25)
			(net 92 "/M.2/C_PCIE0_TX2_P")
			(pintype "passive")
		)
		(pad "2" smd roundrect
			(at 0.48 0)
			(size 0.59 0.64)
			(layers "B.Cu" "B.Paste" "B.Mask")
			(roundrect_rratio 0.25)
			(net 446 "PCIE0_TX2_P")
			(pintype "passive")
		)
	)
	(footprint "antmicro-footprints:R_0402_1005Metric"
		(layer "B.Cu")
		(at 67.2 110.25 90)
		(descr "Resistor SMD 0402")
		(tags "resistor SMD 0402")
		(property "Reference" "R42"
			(at -0.98 0.35 -90)
			(layer "B.SilkS")
			(effects
				(font
					(size 0.7 0.7)
					(thickness 0.15)
				)
				(justify left bottom mirror)
			)
		)
		(property "Value" "R_10k_0402"
			(at 0 -1.4 -90)
			(layer "B.Fab")
			(effects
				(font
					(size 0.7 0.7)
					(thickness 0.15)
				)
				(justify left bottom mirror)
			)
		)
		(property "Footprint" "antmicro-footprints:R_0402_1005Metric"
			(at 0 0 90)
			(layer "F.Fab")
			(hide yes)
			(effects
				(font
					(size 1.27 1.27)
					(thickness 0.15)
				)
			)
		)
		(property "Datasheet" "https://www.bourns.com/docs/product-datasheets/cr.pdf"
			(at 0 0 90)
			(layer "F.Fab")
			(hide yes)
			(effects
				(font
					(size 1.27 1.27)
					(thickness 0.15)
				)
			)
		)
		(property "Author" "Antmicro"
			(at 177.45 43.05 0)
			(layer "B.Fab")
			(hide yes)
			(effects
				(font
					(size 1 1)
					(thickness 0.15)
				)
				(justify mirror)
			)
		)
		(property "License" "Apache-2.0"
			(at 177.45 43.05 0)
			(layer "B.Fab")
			(hide yes)
			(effects
				(font
					(size 1 1)
					(thickness 0.15)
				)
				(justify mirror)
			)
		)
		(property "MPN" "CR0402-FX-1002GLF"
			(at 177.45 43.05 0)
			(layer "B.Fab")
			(hide yes)
			(effects
				(font
					(size 1 1)
					(thickness 0.15)
				)
				(justify mirror)
			)
		)
		(property "Manufacturer" "Bourns"
			(at 177.45 43.05 0)
			(layer "B.Fab")
			(hide yes)
			(effects
				(font
					(size 1 1)
					(thickness 0.15)
				)
				(justify mirror)
			)
		)
		(property "Tolerance" "1%"
			(at 177.45 43.05 0)
			(layer "B.Fab")
			(hide yes)
			(effects
				(font
					(size 1 1)
					(thickness 0.15)
				)
				(justify mirror)
			)
		)
		(property "Val" "10k"
			(at 177.45 43.05 0)
			(layer "B.Fab")
			(hide yes)
			(effects
				(font
					(size 1 1)
					(thickness 0.15)
				)
				(justify mirror)
			)
		)
		(sheetname "USB Debug, DP")
		(sheetfile "usb.kicad_sch")
		(attr smd)
		(fp_rect
			(start -0.925 0.47)
			(end 0.925 -0.47)
			(stroke
				(width 0.05)
				(type default)
			)
			(fill none)
			(layer "B.CrtYd")
		)
		(fp_rect
			(start -0.5 0.25)
			(end 0.5 -0.25)
			(stroke
				(width 0.15)
				(type solid)
			)
			(fill none)
			(layer "B.Fab")
		)
		(fp_text user "${REFERENCE}"
			(at -0.95 -3.168 -90)
			(layer "B.Fab")
			(hide yes)
			(effects
				(font
					(size 0.7 0.7)
					(thickness 0.15)
				)
				(justify left bottom mirror)
			)
		)
		(fp_text user "Author: Antmicro"
			(at -0.95 -4.169 -90)
			(layer "B.Fab")
			(hide yes)
			(effects
				(font
					(size 0.7 0.7)
					(thickness 0.15)
				)
				(justify left bottom mirror)
			)
		)
		(fp_text user "License: Apache-2.0"
			(at -0.95 -5.169 -90)
			(layer "B.Fab")
			(hide yes)
			(effects
				(font
					(size 0.7 0.7)
					(thickness 0.15)
				)
				(justify left bottom mirror)
			)
		)
		(pad "1" smd roundrect
			(at -0.48 0 90)
			(size 0.59 0.64)
			(layers "B.Cu" "B.Paste" "B.Mask")
			(roundrect_rratio 0.25)
			(net 134 "/USB Debug, DP/PDC_LDO_3V3")
			(pintype "passive")
		)
		(pad "2" smd roundrect
			(at 0.48 0 90)
			(size 0.59 0.64)
			(layers "B.Cu" "B.Paste" "B.Mask")
			(roundrect_rratio 0.25)
			(net 286 "/USB Debug, DP/PDC_ADCIN1")
			(pintype "passive")
		)
	)
	(footprint "antmicro-footprints:XDFN-2_1x0.60mm"
		(layer "B.Cu")
		(at 120.25 127.1)
		(property "Reference" "D58"
			(at -1.1 -0.55 180)
			(layer "B.SilkS")
			(effects
				(font
					(size 0.7 0.7)
					(thickness 0.15)
				)
				(justify right bottom mirror)
			)
		)
		(property "Value" "TPD1E0B04_XDFN-2"
			(at 0 -1.5 180)
			(layer "B.Fab")
			(effects
				(font
					(size 0.7 0.7)
					(thickness 0.15)
				)
				(justify left bottom mirror)
			)
		)
		(property "Footprint" "antmicro-footprints:XDFN-2_1x0.60mm"
			(at 0 0 0)
			(layer "F.Fab")
			(hide yes)
			(effects
				(font
					(size 1.27 1.27)
					(thickness 0.15)
				)
			)
		)
		(property "Datasheet" "https://www.ti.com/general/docs/suppproductinfo.tsp?distId=26&gotoUrl=https://www.ti.com/lit/gpn/tpd1e0b04"
			(at 0 0 0)
			(layer "F.Fab")
			(hide yes)
			(effects
				(font
					(size 1.27 1.27)
					(thickness 0.15)
				)
			)
		)
		(property "MPN" "TPD1E0B04DPYR"
			(at 0 0 0)
			(layer "B.Fab")
			(hide yes)
			(effects
				(font
					(size 1 1)
					(thickness 0.15)
				)
				(justify mirror)
			)
		)
		(property "Manufacturer" "Texas Instruments"
			(at 0 0 0)
			(layer "B.Fab")
			(hide yes)
			(effects
				(font
					(size 1 1)
					(thickness 0.15)
				)
				(justify mirror)
			)
		)
		(property "Author" "Antmicro"
			(at 0 0 0)
			(layer "B.Fab")
			(hide yes)
			(effects
				(font
					(size 1 1)
					(thickness 0.15)
				)
				(justify mirror)
			)
		)
		(property "License" "Apache-2.0"
			(at 0 0 0)
			(layer "B.Fab")
			(hide yes)
			(effects
				(font
					(size 1 1)
					(thickness 0.15)
				)
				(justify mirror)
			)
		)
		(sheetname "Peripherals")
		(sheetfile "peripherals.kicad_sch")
		(attr smd)
		(fp_rect
			(start -0.725 0.475)
			(end 0.725 -0.475)
			(stroke
				(width 0.05)
				(type solid)
			)
			(fill none)
			(layer "B.CrtYd")
		)
		(fp_rect
			(start -0.55 0.35)
			(end 0.55 -0.35)
			(stroke
				(width 0.15)
				(type solid)
			)
			(fill none)
			(layer "B.Fab")
		)
		(fp_text user "${REFERENCE}"
			(at -0.8 -3.2 180)
			(layer "B.Fab")
			(hide yes)
			(effects
				(font
					(size 0.7 0.7)
					(thickness 0.15)
				)
				(justify left bottom mirror)
			)
		)
		(fp_text user "License: Apache-2.0"
			(at -0.8 -5.6 180)
			(layer "B.Fab")
			(hide yes)
			(effects
				(font
					(size 0.7 0.7)
					(thickness 0.15)
				)
				(justify left bottom mirror)
			)
		)
		(fp_text user "Author: Antmicro"
			(at -0.8 -4.4 180)
			(layer "B.Fab")
			(hide yes)
			(effects
				(font
					(size 0.7 0.7)
					(thickness 0.15)
				)
				(justify left bottom mirror)
			)
		)
		(pad "1" smd roundrect
			(at -0.351 0)
			(size 0.3 0.5)
			(layers "B.Cu" "B.Paste" "B.Mask")
			(roundrect_rratio 0.25)
			(net 1 "GND")
			(pinfunction "C")
			(pintype "passive")
		)
		(pad "2" smd roundrect
			(at 0.349 0)
			(size 0.3 0.5)
			(layers "B.Cu" "B.Paste" "B.Mask")
			(roundrect_rratio 0.25)
			(net 45 "USER_BTN0")
			(pinfunction "A")
			(pintype "passive")
		)
	)
	(footprint "antmicro-footprints:R_0402_1005Metric"
		(layer "B.Cu")
		(at 52.55 110.15 180)
		(descr "Resistor SMD 0402")
		(tags "resistor SMD 0402")
		(property "Reference" "R111"
			(at -1.122484 0.772697 0)
			(layer "B.SilkS")
			(effects
				(font
					(size 0.7 0.7)
					(thickness 0.15)
				)
				(justify left bottom mirror)
			)
		)
		(property "Value" "R_1k_0402"
			(at -1.011843 -1.772047 0)
			(layer "B.Fab")
			(effects
				(font
					(size 0.7 0.7)
					(thickness 0.15)
				)
				(justify left bottom mirror)
			)
		)
		(property "Footprint" "antmicro-footprints:R_0402_1005Metric"
			(at 0 0 180)
			(layer "F.Fab")
			(hide yes)
			(effects
				(font
					(size 1.27 1.27)
					(thickness 0.15)
				)
			)
		)
		(property "Datasheet" "https://www.bourns.com/docs/product-datasheets/cr.pdf"
			(at 0 0 180)
			(layer "F.Fab")
			(hide yes)
			(effects
				(font
					(size 1.27 1.27)
					(thickness 0.15)
				)
			)
		)
		(property "Author" "Antmicro"
			(at 105.1 220.3 0)
			(layer "B.Fab")
			(hide yes)
			(effects
				(font
					(size 1 1)
					(thickness 0.15)
				)
				(justify mirror)
			)
		)
		(property "License" "Apache-2.0"
			(at 105.1 220.3 0)
			(layer "B.Fab")
			(hide yes)
			(effects
				(font
					(size 1 1)
					(thickness 0.15)
				)
				(justify mirror)
			)
		)
		(property "MPN" "CR0402-FX-1001GLF"
			(at 105.1 220.3 0)
			(layer "B.Fab")
			(hide yes)
			(effects
				(font
					(size 1 1)
					(thickness 0.15)
				)
				(justify mirror)
			)
		)
		(property "Manufacturer" "Bourns"
			(at 105.1 220.3 0)
			(layer "B.Fab")
			(hide yes)
			(effects
				(font
					(size 1 1)
					(thickness 0.15)
				)
				(justify mirror)
			)
		)
		(property "Tolerance" "1%"
			(at 105.1 220.3 0)
			(layer "B.Fab")
			(hide yes)
			(effects
				(font
					(size 1 1)
					(thickness 0.15)
				)
				(justify mirror)
			)
		)
		(property "Val" "1k"
			(at 105.1 220.3 0)
			(layer "B.Fab")
			(hide yes)
			(effects
				(font
					(size 1 1)
					(thickness 0.15)
				)
				(justify mirror)
			)
		)
		(sheetname "USB Debug, DP")
		(sheetfile "usb.kicad_sch")
		(attr smd)
		(fp_rect
			(start -0.925 0.47)
			(end 0.925 -0.47)
			(stroke
				(width 0.05)
				(type default)
			)
			(fill none)
			(layer "B.CrtYd")
		)
		(fp_rect
			(start -0.5 0.25)
			(end 0.5 -0.25)
			(stroke
				(width 0.15)
				(type solid)
			)
			(fill none)
			(layer "B.Fab")
		)
		(fp_text user "License: Apache-2.0"
			(at -0.95 -5.169 0)
			(layer "B.Fab")
			(hide yes)
			(effects
				(font
					(size 0.7 0.7)
					(thickness 0.15)
				)
				(justify left bottom mirror)
			)
		)
		(fp_text user "${REFERENCE}"
			(at -0.95 -3.168 0)
			(layer "B.Fab")
			(hide yes)
			(effects
				(font
					(size 0.7 0.7)
					(thickness 0.15)
				)
				(justify left bottom mirror)
			)
		)
		(fp_text user "Author: Antmicro"
			(at -0.95 -4.169 0)
			(layer "B.Fab")
			(hide yes)
			(effects
				(font
					(size 0.7 0.7)
					(thickness 0.15)
				)
				(justify left bottom mirror)
			)
		)
		(pad "1" smd roundrect
			(at -0.48 0 180)
			(size 0.59 0.64)
			(layers "B.Cu" "B.Paste" "B.Mask")
			(roundrect_rratio 0.25)
			(net 398 "/USB Debug, DP/FTDI_CBUS3{slash}SCL")
			(pintype "passive")
		)
		(pad "2" smd roundrect
			(at 0.48 0 180)
			(size 0.59 0.64)
			(layers "B.Cu" "B.Paste" "B.Mask")
			(roundrect_rratio 0.25)
			(net 185 "/USB Debug, DP/FTDI_3V3")
			(pintype "passive")
		)
	)
)
